(kicad_pcb
	(version 20260206)
	(generator "pcbnew")
	(generator_version "10.0")
	(general
		(thickness 1.6)
		(legacy_teardrops no)
	)
	(paper "A4")
	(title_block
		(title "01162023_DA0F0TEBIF0_F0T_Expander_BD_F_brd_V02_OCP.brd")
		(comment 1 "Grand Teton / footprints 6884-6889 of 9728")
	)
	(layers
		(0 "F.Cu" signal "TOP")
		(4 "In1.Cu" signal "GND")
		(6 "In2.Cu" signal "VCC")
		(8 "In3.Cu" signal "VCC1")
		(10 "In4.Cu" signal "GND1")
		(12 "In5.Cu" signal "IN1")
		(14 "In6.Cu" signal "GND2")
		(16 "In7.Cu" signal "IN2")
		(18 "In8.Cu" signal "GND3")
		(20 "In9.Cu" signal "IN3")
		(22 "In10.Cu" signal "GND4")
		(24 "In11.Cu" signal "IN4")
		(26 "In12.Cu" signal "GND5")
		(28 "In13.Cu" signal "IN5")
		(30 "In14.Cu" signal "GND6")
		(32 "In15.Cu" signal "IN6")
		(34 "In16.Cu" signal "GND7")
		(2 "B.Cu" signal "BOTTOM")
		(9 "F.Adhes" user "F.Adhesive")
		(11 "B.Adhes" user "B.Adhesive")
		(13 "F.Paste" user "Package Geometry/Pastemask Top")
		(15 "B.Paste" user "Package Geometry/Pastemask Bottom")
		(5 "F.SilkS" user "Ref Des/Silkscreen Top")
		(7 "B.SilkS" user "Ref Des/Silkscreen Bottom")
		(1 "F.Mask" user "Board Geometry/Soldermask Top")
		(3 "B.Mask" user "Board Geometry/Soldermask Bottom")
		(17 "Dwgs.User" user "User.Drawings")
		(19 "Cmts.User" user "User.Comments")
		(21 "Eco1.User" user "User.Eco1")
		(23 "Eco2.User" user "User.Eco2")
		(25 "Edge.Cuts" user "Board Geometry/Outline")
		(27 "Margin" user)
		(31 "F.CrtYd" user "Package Geometry/Place Bound Top")
		(29 "B.CrtYd" user "Package Geometry/Place Bound Bottom")
		(35 "F.Fab" user "Ref Des/Assembly Top")
		(33 "B.Fab" user "Ref Des/Assembly Bottom")
	)
	(footprint ""
		(layer "F.Cu")
		(at 400.884136 -29.222954 -90)
		(property "Reference" "PC968"
			(at 0 0 270)
			(layer "F.SilkS")
			(hide yes)
			(effects
				(font
					(size 1.27 1.27)
				)
			)
		)
		(property "Value" ""
			(at 0 0 270)
			(layer "F.Fab")
			(effects
				(font
					(size 1.27 1.27)
				)
			)
		)
		(duplicate_pad_numbers_are_jumpers no)
		(fp_line
			(start -0.7874 0.4064)
			(end -0.7874 -0.4064)
			(stroke
				(width 0.1524)
				(type default)
			)
			(layer "F.SilkS")
		)
		(fp_line
			(start 0.7874 0.4064)
			(end -0.7874 0.4064)
			(stroke
				(width 0.1524)
				(type default)
			)
			(layer "F.SilkS")
		)
		(fp_line
			(start -0.7874 -0.4064)
			(end 0.7874 -0.4064)
			(stroke
				(width 0.1524)
				(type default)
			)
			(layer "F.SilkS")
		)
		(fp_line
			(start 0.7874 -0.4064)
			(end 0.7874 0.4064)
			(stroke
				(width 0.1524)
				(type default)
			)
			(layer "F.SilkS")
		)
		(fp_line
			(start -0.67945 0.3048)
			(end -0.67945 -0.305054)
			(stroke
				(width 0.1)
				(type default)
			)
			(layer "F.Fab")
		)
		(fp_line
			(start -0.12065 0.3048)
			(end -0.67945 0.3048)
			(stroke
				(width 0.1)
				(type default)
			)
			(layer "F.Fab")
		)
		(fp_line
			(start 0.120396 0.3048)
			(end 0.120396 0.2794)
			(stroke
				(width 0.1)
				(type default)
			)
			(layer "F.Fab")
		)
		(fp_line
			(start 0.67945 0.3048)
			(end 0.120396 0.3048)
			(stroke
				(width 0.1)
				(type default)
			)
			(layer "F.Fab")
		)
		(fp_line
			(start -0.12065 0.2794)
			(end -0.12065 0.3048)
			(stroke
				(width 0.1)
				(type default)
			)
			(layer "F.Fab")
		)
		(fp_line
			(start 0.120396 0.2794)
			(end -0.12065 0.2794)
			(stroke
				(width 0.1)
				(type default)
			)
			(layer "F.Fab")
		)
		(fp_line
			(start -0.12065 -0.2794)
			(end 0.12065 -0.2794)
			(stroke
				(width 0.1)
				(type default)
			)
			(layer "F.Fab")
		)
		(fp_line
			(start 0.12065 -0.2794)
			(end 0.12065 -0.3048)
			(stroke
				(width 0.1)
				(type default)
			)
			(layer "F.Fab")
		)
		(fp_line
			(start 0.12065 -0.3048)
			(end 0.67945 -0.3048)
			(stroke
				(width 0.1)
				(type default)
			)
			(layer "F.Fab")
		)
		(fp_line
			(start 0.67945 -0.3048)
			(end 0.67945 0.3048)
			(stroke
				(width 0.1)
				(type default)
			)
			(layer "F.Fab")
		)
		(fp_line
			(start -0.67945 -0.305054)
			(end -0.12065 -0.305054)
			(stroke
				(width 0.1)
				(type default)
			)
			(layer "F.Fab")
		)
		(fp_line
			(start -0.12065 -0.305054)
			(end -0.12065 -0.2794)
			(stroke
				(width 0.1)
				(type default)
			)
			(layer "F.Fab")
		)
		(pad "1" smd circle
			(at -0.40005 0 270)
			(size 0 0)
			(layers "F.Cu" "F.Mask" "F.Paste")
			(net "P3V3_AUX")
		)
		(pad "2" smd circle
			(at 0.40005 0 270)
			(size 0 0)
			(layers "F.Cu" "F.Mask" "F.Paste")
			(net "GND")
		)
	)
	(footprint ""
		(layer "F.Cu")
		(at 409.92679 -389.955532 180)
		(property "Reference" "C4159"
			(at 0 0 180)
			(layer "F.SilkS")
			(hide yes)
			(effects
				(font
					(size 1.27 1.27)
				)
			)
		)
		(property "Value" ""
			(at 0 0 180)
			(layer "F.Fab")
			(effects
				(font
					(size 1.27 1.27)
				)
			)
		)
		(duplicate_pad_numbers_are_jumpers no)
		(fp_line
			(start 0.7874 0.4064)
			(end -0.7874 0.4064)
			(stroke
				(width 0.1524)
				(type default)
			)
			(layer "F.SilkS")
		)
		(fp_line
			(start 0.7874 -0.4064)
			(end 0.7874 0.4064)
			(stroke
				(width 0.1524)
				(type default)
			)
			(layer "F.SilkS")
		)
		(fp_line
			(start -0.7874 0.4064)
			(end -0.7874 -0.4064)
			(stroke
				(width 0.1524)
				(type default)
			)
			(layer "F.SilkS")
		)
		(fp_line
			(start -0.7874 -0.4064)
			(end 0.7874 -0.4064)
			(stroke
				(width 0.1524)
				(type default)
			)
			(layer "F.SilkS")
		)
		(fp_line
			(start 0.67945 0.3048)
			(end 0.120396 0.3048)
			(stroke
				(width 0.1)
				(type default)
			)
			(layer "F.Fab")
		)
		(fp_line
			(start 0.67945 -0.3048)
			(end 0.67945 0.3048)
			(stroke
				(width 0.1)
				(type default)
			)
			(layer "F.Fab")
		)
		(fp_line
			(start 0.12065 -0.2794)
			(end 0.12065 -0.3048)
			(stroke
				(width 0.1)
				(type default)
			)
			(layer "F.Fab")
		)
		(fp_line
			(start 0.12065 -0.3048)
			(end 0.67945 -0.3048)
			(stroke
				(width 0.1)
				(type default)
			)
			(layer "F.Fab")
		)
		(fp_line
			(start 0.120396 0.3048)
			(end 0.120396 0.2794)
			(stroke
				(width 0.1)
				(type default)
			)
			(layer "F.Fab")
		)
		(fp_line
			(start 0.120396 0.2794)
			(end -0.12065 0.2794)
			(stroke
				(width 0.1)
				(type default)
			)
			(layer "F.Fab")
		)
		(fp_line
			(start -0.12065 0.3048)
			(end -0.67945 0.3048)
			(stroke
				(width 0.1)
				(type default)
			)
			(layer "F.Fab")
		)
		(fp_line
			(start -0.12065 0.2794)
			(end -0.12065 0.3048)
			(stroke
				(width 0.1)
				(type default)
			)
			(layer "F.Fab")
		)
		(fp_line
			(start -0.12065 -0.2794)
			(end 0.12065 -0.2794)
			(stroke
				(width 0.1)
				(type default)
			)
			(layer "F.Fab")
		)
		(fp_line
			(start -0.12065 -0.305054)
			(end -0.12065 -0.2794)
			(stroke
				(width 0.1)
				(type default)
			)
			(layer "F.Fab")
		)
		(fp_line
			(start -0.67945 0.3048)
			(end -0.67945 -0.305054)
			(stroke
				(width 0.1)
				(type default)
			)
			(layer "F.Fab")
		)
		(fp_line
			(start -0.67945 -0.305054)
			(end -0.12065 -0.305054)
			(stroke
				(width 0.1)
				(type default)
			)
			(layer "F.Fab")
		)
		(pad "1" smd circle
			(at -0.40005 0 180)
			(size 0 0)
			(layers "F.Cu" "F.Mask" "F.Paste")
			(net "GND")
		)
		(pad "2" smd circle
			(at 0.40005 0 180)
			(size 0 0)
			(layers "F.Cu" "F.Mask" "F.Paste")
			(net "GPU_3V3IO_RSVD1")
		)
	)
	(footprint ""
		(layer "F.Cu")
		(at 106.52506 -128.045464 -90)
		(property "Reference" "PD3"
			(at 3.839464 2.07899 90)
			(unlocked yes)
			(layer "F.SilkS")
			(effects
				(font
					(size 0.7874 0.5842)
					(thickness 0.1524)
				)
				(justify left)
			)
		)
		(property "Value" ""
			(at 0 0 270)
			(layer "F.Fab")
			(effects
				(font
					(size 1.27 1.27)
				)
			)
		)
		(duplicate_pad_numbers_are_jumpers no)
		(fp_line
			(start -3.400044 1.459992)
			(end -3.400044 -1.459992)
			(stroke
				(width 0.1524)
				(type default)
			)
			(layer "F.SilkS")
		)
		(fp_line
			(start 4.107942 1.459992)
			(end -3.400044 1.459992)
			(stroke
				(width 0.1524)
				(type default)
			)
			(layer "F.SilkS")
		)
		(fp_line
			(start -3.400044 -1.459992)
			(end 4.107942 -1.459992)
			(stroke
				(width 0.1524)
				(type default)
			)
			(layer "F.SilkS")
		)
		(fp_line
			(start 4.107942 -1.459992)
			(end 4.107942 1.459992)
			(stroke
				(width 0.1524)
				(type default)
			)
			(layer "F.SilkS")
		)
		(fp_poly
			(pts
				(xy 4.107942 -1.459992) (xy 4.107942 1.459992) (xy 3.308096 1.459992) (xy 3.308096 -1.459992)
			)
			(stroke
				(width 0)
				(type default)
			)
			(fill yes)
			(layer "F.SilkS")
		)
		(fp_line
			(start -2.29997 1.459992)
			(end -2.29997 -1.459992)
			(stroke
				(width 0.1)
				(type default)
			)
			(layer "F.Fab")
		)
		(fp_line
			(start 2.29997 1.459992)
			(end -2.29997 1.459992)
			(stroke
				(width 0.1)
				(type default)
			)
			(layer "F.Fab")
		)
		(fp_line
			(start -2.29997 -1.459992)
			(end 2.29997 -1.459992)
			(stroke
				(width 0.1)
				(type default)
			)
			(layer "F.Fab")
		)
		(fp_line
			(start 2.29997 -1.459992)
			(end 2.29997 1.459992)
			(stroke
				(width 0.1)
				(type default)
			)
			(layer "F.Fab")
		)
		(fp_text user "-"
			(at 5.4102 0.29845 90)
			(unlocked yes)
			(layer "F.SilkS")
			(effects
				(font
					(size 1.905 1.4224)
					(thickness 0.1524)
				)
				(justify left)
			)
		)
		(fp_text user "+"
			(at -4.7752 -0.12065 270)
			(unlocked yes)
			(layer "F.SilkS")
			(effects
				(font
					(size 1.905 1.4224)
					(thickness 0.1524)
				)
				(justify left)
			)
		)
		(fp_text user "-"
			(at 5.4102 0.29845 90)
			(unlocked yes)
			(layer "F.Fab")
			(effects
				(font
					(size 1.905 1.4224)
					(thickness 0.1524)
				)
				(justify left)
			)
		)
		(fp_text user "+"
			(at -4.7752 -0.12065 270)
			(unlocked yes)
			(layer "F.Fab")
			(effects
				(font
					(size 1.905 1.4224)
					(thickness 0.1524)
				)
				(justify left)
			)
		)
		(pad "A" smd rect
			(at -1.999996 0)
			(size 1.7018 2.5146)
			(layers "F.Cu" "F.Mask" "F.Paste")
			(net "GND")
		)
		(pad "C" smd rect
			(at 1.999996 0)
			(size 1.7018 2.5146)
			(layers "F.Cu" "F.Mask" "F.Paste")
			(net "P3V3")
		)
	)
	(footprint ""
		(layer "F.Cu")
		(at 336.443574 -44.87291)
		(property "Reference" "R628"
			(at 0 0 0)
			(layer "F.SilkS")
			(hide yes)
			(effects
				(font
					(size 1.27 1.27)
				)
			)
		)
		(property "Value" ""
			(at 0 0 0)
			(layer "F.Fab")
			(effects
				(font
					(size 1.27 1.27)
				)
			)
		)
		(duplicate_pad_numbers_are_jumpers no)
		(fp_line
			(start -0.7874 -0.4064)
			(end 0.7874 -0.4064)
			(stroke
				(width 0.1524)
				(type default)
			)
			(layer "F.SilkS")
		)
		(fp_line
			(start -0.7874 0.4064)
			(end -0.7874 -0.4064)
			(stroke
				(width 0.1524)
				(type default)
			)
			(layer "F.SilkS")
		)
		(fp_line
			(start 0.7874 -0.4064)
			(end 0.7874 0.4064)
			(stroke
				(width 0.1524)
				(type default)
			)
			(layer "F.SilkS")
		)
		(fp_line
			(start 0.7874 0.4064)
			(end -0.7874 0.4064)
			(stroke
				(width 0.1524)
				(type default)
			)
			(layer "F.SilkS")
		)
		(fp_line
			(start -0.67945 -0.305054)
			(end -0.12065 -0.305054)
			(stroke
				(width 0.1)
				(type default)
			)
			(layer "F.Fab")
		)
		(fp_line
			(start -0.67945 0.3048)
			(end -0.67945 -0.305054)
			(stroke
				(width 0.1)
				(type default)
			)
			(layer "F.Fab")
		)
		(fp_line
			(start -0.12065 -0.305054)
			(end -0.12065 -0.2794)
			(stroke
				(width 0.1)
				(type default)
			)
			(layer "F.Fab")
		)
		(fp_line
			(start -0.12065 -0.2794)
			(end 0.12065 -0.2794)
			(stroke
				(width 0.1)
				(type default)
			)
			(layer "F.Fab")
		)
		(fp_line
			(start -0.12065 0.2794)
			(end -0.12065 0.3048)
			(stroke
				(width 0.1)
				(type default)
			)
			(layer "F.Fab")
		)
		(fp_line
			(start -0.12065 0.3048)
			(end -0.67945 0.3048)
			(stroke
				(width 0.1)
				(type default)
			)
			(layer "F.Fab")
		)
		(fp_line
			(start 0.120396 0.2794)
			(end -0.12065 0.2794)
			(stroke
				(width 0.1)
				(type default)
			)
			(layer "F.Fab")
		)
		(fp_line
			(start 0.120396 0.3048)
			(end 0.120396 0.2794)
			(stroke
				(width 0.1)
				(type default)
			)
			(layer "F.Fab")
		)
		(fp_line
			(start 0.12065 -0.3048)
			(end 0.67945 -0.3048)
			(stroke
				(width 0.1)
				(type default)
			)
			(layer "F.Fab")
		)
		(fp_line
			(start 0.12065 -0.2794)
			(end 0.12065 -0.3048)
			(stroke
				(width 0.1)
				(type default)
			)
			(layer "F.Fab")
		)
		(fp_line
			(start 0.67945 -0.3048)
			(end 0.67945 0.3048)
			(stroke
				(width 0.1)
				(type default)
			)
			(layer "F.Fab")
		)
		(fp_line
			(start 0.67945 0.3048)
			(end 0.120396 0.3048)
			(stroke
				(width 0.1)
				(type default)
			)
			(layer "F.Fab")
		)
		(pad "1" smd circle
			(at -0.40005 0)
			(size 0 0)
			(layers "F.Cu" "F.Mask" "F.Paste")
			(net "SSD11_ADC_A0")
		)
		(pad "2" smd circle
			(at 0.40005 0)
			(size 0 0)
			(layers "F.Cu" "F.Mask" "F.Paste")
			(net "P3V3_AUX")
		)
	)
	(footprint ""
		(layer "F.Cu")
		(at 239.550194 -62.551056 90)
		(property "Reference" "Q204"
			(at -0.219456 -2.058924 90)
			(unlocked yes)
			(layer "F.SilkS")
			(effects
				(font
					(size 0.7874 0.5842)
					(thickness 0.1524)
				)
			)
		)
		(property "Value" ""
			(at 0 0 90)
			(layer "F.Fab")
			(effects
				(font
					(size 1.27 1.27)
				)
			)
		)
		(duplicate_pad_numbers_are_jumpers no)
		(fp_line
			(start 1.376172 -1.199896)
			(end 1.376172 1.199896)
			(stroke
				(width 0.1524)
				(type default)
			)
			(layer "F.SilkS")
		)
		(fp_line
			(start 0.508 -1.199896)
			(end 1.376172 -1.199896)
			(stroke
				(width 0.1524)
				(type default)
			)
			(layer "F.SilkS")
		)
		(fp_line
			(start -0.508 -1.199896)
			(end 0 -0.762)
			(stroke
				(width 0.1524)
				(type default)
			)
			(layer "F.SilkS")
		)
		(fp_line
			(start -1.376172 -1.199896)
			(end -0.508 -1.199896)
			(stroke
				(width 0.1524)
				(type default)
			)
			(layer "F.SilkS")
		)
		(fp_line
			(start 0 -0.762)
			(end 0.508 -1.199896)
			(stroke
				(width 0.1524)
				(type default)
			)
			(layer "F.SilkS")
		)
		(fp_line
			(start 1.376172 1.199896)
			(end -1.376172 1.199896)
			(stroke
				(width 0.1524)
				(type default)
			)
			(layer "F.SilkS")
		)
		(fp_line
			(start -1.376172 1.199896)
			(end -1.376172 -1.199896)
			(stroke
				(width 0.1524)
				(type default)
			)
			(layer "F.SilkS")
		)
		(fp_poly
			(pts
				(xy -1.299972 -0.794004) (xy -2.061972 -1.175004) (xy -2.061972 -0.413004)
			)
			(stroke
				(width 0)
				(type default)
			)
			(fill yes)
			(layer "F.SilkS")
		)
		(fp_line
			(start 0.674878 -1.100074)
			(end 0.674878 1.100074)
			(stroke
				(width 0.1)
				(type default)
			)
			(layer "F.Fab")
		)
		(fp_line
			(start -0.674878 -1.100074)
			(end 0.674878 -1.100074)
			(stroke
				(width 0.1)
				(type default)
			)
			(layer "F.Fab")
		)
		(fp_line
			(start 0.674878 1.100074)
			(end -0.674878 1.100074)
			(stroke
				(width 0.1)
				(type default)
			)
			(layer "F.Fab")
		)
		(fp_line
			(start -0.674878 1.100074)
			(end -0.674878 -1.100074)
			(stroke
				(width 0.1)
				(type default)
			)
			(layer "F.Fab")
		)
		(fp_poly
			(pts
				(xy -1.4605 -0.7493) (xy -2.2225 -1.1303) (xy -2.2225 -0.3683)
			)
			(stroke
				(width 0)
				(type default)
			)
			(fill yes)
			(layer "F.Fab")
		)
		(pad "1" smd rect
			(at -0.899922 -0.750062)
			(size 0.6096 0.6096)
			(layers "F.Cu" "F.Mask" "F.Paste")
			(net "GND")
		)
		(pad "2" smd rect
			(at -0.899922 0)
			(size 0.4064 0.6096)
			(layers "F.Cu" "F.Mask" "F.Paste")
			(net "P12V_SSD8_PG_G1")
		)
		(pad "3" smd rect
			(at -0.899922 0.750062)
			(size 0.6096 0.6096)
			(layers "F.Cu" "F.Mask" "F.Paste")
			(net "PWRGD_P12V_SSD8_D")
		)
		(pad "4" smd rect
			(at 0.899922 0.750062)
			(size 0.6096 0.6096)
			(layers "F.Cu" "F.Mask" "F.Paste")
			(net "GND")
		)
		(pad "5" smd rect
			(at 0.899922 0)
			(size 0.4064 0.6096)
			(layers "F.Cu" "F.Mask" "F.Paste")
			(net "P12V_SSD8_PG_G2")
		)
		(pad "6" smd rect
			(at 0.899922 -0.750062)
			(size 0.6096 0.6096)
			(layers "F.Cu" "F.Mask" "F.Paste")
			(net "P12V_SSD8_PG_G2")
		)
	)
	(footprint ""
		(layer "F.Cu")
		(at 127.034544 -303.649634 90)
		(property "Reference" "PC102"
			(at 0 0 90)
			(layer "F.SilkS")
			(hide yes)
			(effects
				(font
					(size 1.27 1.27)
				)
			)
		)
		(property "Value" ""
			(at 0 0 90)
			(layer "F.Fab")
			(effects
				(font
					(size 1.27 1.27)
				)
			)
		)
		(duplicate_pad_numbers_are_jumpers no)
		(fp_line
			(start 1.524 -0.762)
			(end 1.524 0.762)
			(stroke
				(width 0.1524)
				(type default)
			)
			(layer "F.SilkS")
		)
		(fp_line
			(start -1.524 -0.762)
			(end 1.524 -0.762)
			(stroke
				(width 0.1524)
				(type default)
			)
			(layer "F.SilkS")
		)
		(fp_line
			(start 1.524 0.762)
			(end -1.524 0.762)
			(stroke
				(width 0.1524)
				(type default)
			)
			(layer "F.SilkS")
		)
		(fp_line
			(start -1.524 0.762)
			(end -1.524 -0.762)
			(stroke
				(width 0.1524)
				(type default)
			)
			(layer "F.SilkS")
		)
		(fp_line
			(start 1.1049 -0.724916)
			(end -1.1049 -0.724916)
			(stroke
				(width 0.1)
				(type default)
			)
			(layer "F.Fab")
		)
		(fp_line
			(start -1.1049 -0.724916)
			(end -1.1049 0.724916)
			(stroke
				(width 0.1)
				(type default)
			)
			(layer "F.Fab")
		)
		(fp_line
			(start 1.1049 0.724916)
			(end 1.1049 -0.724916)
			(stroke
				(width 0.1)
				(type default)
			)
			(layer "F.Fab")
		)
		(fp_line
			(start -1.1049 0.724916)
			(end 1.1049 0.724916)
			(stroke
				(width 0.1)
				(type default)
			)
			(layer "F.Fab")
		)
		(pad "1" smd rect
			(at -0.889 0 270)
			(size 1.016 1.27)
			(layers "F.Cu" "F.Mask" "F.Paste")
			(net "P0V8_PEX1")
		)
		(pad "2" smd rect
			(at 0.889 0 270)
			(size 1.016 1.27)
			(layers "F.Cu" "F.Mask" "F.Paste")
			(net "GND")
		)
	)
)
